(kicad_pcb
	(version 20260206)
	(generator "pcbnew")
	(generator_version "10.0")
	(general
		(thickness 1.6)
		(legacy_teardrops no)
	)
	(paper "A4")
	(title_block
		(title "04192023_DAF0TMB3IC0_F0TG_MB_C_brd_V02_OCP.brd")
		(comment 1 "Grand Teton / footprints 4649-4654 of 8354")
	)
	(layers
		(0 "F.Cu" signal "TOP")
		(4 "In1.Cu" signal "GND")
		(6 "In2.Cu" signal "IN1")
		(8 "In3.Cu" signal "GND1")
		(10 "In4.Cu" signal "IN2")
		(12 "In5.Cu" signal "GND2")
		(14 "In6.Cu" signal "IN3")
		(16 "In7.Cu" signal "GND3")
		(18 "In8.Cu" signal "VCC")
		(20 "In9.Cu" signal "VCC1")
		(22 "In10.Cu" signal "GND4")
		(24 "In11.Cu" signal "IN4")
		(26 "In12.Cu" signal "GND5")
		(28 "In13.Cu" signal "IN5")
		(30 "In14.Cu" signal "GND6")
		(32 "In15.Cu" signal "IN6")
		(34 "In16.Cu" signal "GND7")
		(2 "B.Cu" signal "BOTTOM")
		(9 "F.Adhes" user "F.Adhesive")
		(11 "B.Adhes" user "B.Adhesive")
		(13 "F.Paste" user "Package Geometry/Pastemask Top")
		(15 "B.Paste" user "Package Geometry/Pastemask Bottom")
		(5 "F.SilkS" user "Ref Des/Silkscreen Top")
		(7 "B.SilkS" user "Ref Des/Silkscreen Bottom")
		(1 "F.Mask" user "Board Geometry/Soldermask Top")
		(3 "B.Mask" user "Board Geometry/Soldermask Bottom")
		(17 "Dwgs.User" user "User.Drawings")
		(19 "Cmts.User" user "User.Comments")
		(21 "Eco1.User" user "User.Eco1")
		(23 "Eco2.User" user "User.Eco2")
		(25 "Edge.Cuts" user "Board Geometry/Outline")
		(27 "Margin" user)
		(31 "F.CrtYd" user "Package Geometry/Place Bound Top")
		(29 "B.CrtYd" user "Package Geometry/Place Bound Bottom")
		(35 "F.Fab" user "Ref Des/Assembly Top")
		(33 "B.Fab" user "Ref Des/Assembly Bottom")
	)
	(footprint ""
		(layer "F.Cu")
		(at 308.696106 -346.71635)
		(property "Reference" "PU14"
			(at -6.182106 -6.82498 0)
			(unlocked yes)
			(layer "F.SilkS")
			(effects
				(font
					(size 0.7874 0.5842)
					(thickness 0.1524)
				)
				(justify left)
			)
		)
		(property "Value" ""
			(at 0 0 0)
			(layer "F.Fab")
			(effects
				(font
					(size 1.27 1.27)
				)
			)
		)
		(duplicate_pad_numbers_are_jumpers no)
		(fp_line
			(start -2.500122 -2.999994)
			(end -2.24409 -2.999994)
			(stroke
				(width 0.1524)
				(type default)
			)
			(layer "F.SilkS")
		)
		(fp_line
			(start -2.500122 -2.529078)
			(end -2.500122 -2.999994)
			(stroke
				(width 0.1524)
				(type default)
			)
			(layer "F.SilkS")
		)
		(fp_line
			(start -2.500122 0.6604)
			(end -2.500122 0.229108)
			(stroke
				(width 0.1524)
				(type default)
			)
			(layer "F.SilkS")
		)
		(fp_line
			(start -2.500122 2.999994)
			(end -2.500122 2.339594)
			(stroke
				(width 0.1524)
				(type default)
			)
			(layer "F.SilkS")
		)
		(fp_line
			(start -2.2987 2.999994)
			(end -2.500122 2.999994)
			(stroke
				(width 0.1524)
				(type default)
			)
			(layer "F.SilkS")
		)
		(fp_line
			(start 2.31394 -2.999994)
			(end 2.500122 -2.999994)
			(stroke
				(width 0.1524)
				(type default)
			)
			(layer "F.SilkS")
		)
		(fp_line
			(start 2.500122 -2.999994)
			(end 2.500122 -2.44348)
			(stroke
				(width 0.1524)
				(type default)
			)
			(layer "F.SilkS")
		)
		(fp_line
			(start 2.500122 2.339594)
			(end 2.500122 2.999994)
			(stroke
				(width 0.1524)
				(type default)
			)
			(layer "F.SilkS")
		)
		(fp_line
			(start 2.500122 2.999994)
			(end 2.2987 2.999994)
			(stroke
				(width 0.1524)
				(type default)
			)
			(layer "F.SilkS")
		)
		(fp_poly
			(pts
				(xy -3.438652 -2.681478) (xy -2.968752 -3.151378) (xy -2.734056 -2.446782)
			)
			(stroke
				(width 0)
				(type default)
			)
			(fill yes)
			(layer "F.SilkS")
		)
		(fp_line
			(start -2.500122 -2.999994)
			(end 2.500122 -2.999994)
			(stroke
				(width 0.1)
				(type default)
			)
			(layer "F.Fab")
		)
		(fp_line
			(start -2.500122 2.999994)
			(end -2.500122 -2.999994)
			(stroke
				(width 0.1)
				(type default)
			)
			(layer "F.Fab")
		)
		(fp_line
			(start 2.500122 -2.999994)
			(end 2.500122 2.999994)
			(stroke
				(width 0.1)
				(type default)
			)
			(layer "F.Fab")
		)
		(fp_line
			(start 2.500122 2.999994)
			(end -2.500122 2.999994)
			(stroke
				(width 0.1)
				(type default)
			)
			(layer "F.Fab")
		)
		(fp_poly
			(pts
				(xy -4.218432 -2.783078) (xy -4.218432 -1.767078) (xy -3.202432 -2.275078)
			)
			(stroke
				(width 0)
				(type default)
			)
			(fill yes)
			(layer "F.Fab")
		)
		(pad "1" smd rect
			(at -2.400046 -2.275078 90)
			(size 0.2286 0.6096)
			(layers "F.Cu" "F.Mask" "F.Paste")
			(net "PVDDCR_CPU1_P0_VOS4")
		)
		(pad "2" smd rect
			(at -2.400046 -1.82499 90)
			(size 0.2286 0.6096)
			(layers "F.Cu" "F.Mask" "F.Paste")
			(net "GND")
		)
		(pad "3" smd rect
			(at -2.400046 -1.374902 90)
			(size 0.2286 0.6096)
			(layers "F.Cu" "F.Mask" "F.Paste")
			(net "PVDDCR_CPU1_P0_VCC4")
		)
		(pad "4" smd rect
			(at -2.400046 -0.925068 90)
			(size 0.2286 0.6096)
			(layers "F.Cu" "F.Mask" "F.Paste")
			(net "PVDDCR_CPU1_P0_PVCC")
		)
		(pad "5" smd rect
			(at -2.400046 -0.47498 90)
			(size 0.2286 0.6096)
			(layers "F.Cu" "F.Mask" "F.Paste")
			(net "GND")
		)
		(pad "6" smd rect
			(at -2.400046 -0.024892 90)
			(size 0.2286 0.6096)
			(layers "F.Cu" "F.Mask" "F.Paste")
			(net "NC_PVDDCR_CPU1_P0_GL1_4")
		)
		(pad "7_9-20_24" smd circle
			(at 0 1.150112 90)
			(size 0 0)
			(layers "F.Cu" "F.Mask" "F.Paste")
			(net "GND")
		)
		(pad "10_19" smd rect
			(at 0 2.899918 90)
			(size 0.6096 4.318)
			(layers "F.Cu" "F.Mask" "F.Paste")
			(net "SW_PVDDCR_CPU1_P0_SW4")
		)
		(pad "25_29" smd rect
			(at 1.549908 -1.279906 270)
			(size 2.0574 2.3114)
			(layers "F.Cu" "F.Mask" "F.Paste")
			(net "SW_P12V_AUX_PVDDCR_CPU1_P0_FLT")
		)
		(pad "30" smd rect
			(at 2.05994 -2.899918)
			(size 0.2286 0.6096)
			(layers "F.Cu" "F.Mask" "F.Paste")
			(net "SW_P12V_AUX_PVDDCR_CPU1_P0_FLT")
		)
		(pad "31" smd rect
			(at 1.610106 -2.899918)
			(size 0.2286 0.6096)
			(layers "F.Cu" "F.Mask" "F.Paste")
			(net "NC_PVDDCR_CPU1_P0_DNC4")
		)
		(pad "32" smd rect
			(at 1.160018 -2.899918)
			(size 0.2286 0.6096)
			(layers "F.Cu" "F.Mask" "F.Paste")
			(net "SW_PVDDCR_CPU1_P0_BOOTR4")
		)
		(pad "33" smd rect
			(at 0.70993 -2.899918)
			(size 0.2286 0.6096)
			(layers "F.Cu" "F.Mask" "F.Paste")
			(net "SW_PVDDCR_CPU1_P0_BOOT4")
		)
		(pad "34" smd rect
			(at 0.260096 -2.899918)
			(size 0.2286 0.6096)
			(layers "F.Cu" "F.Mask" "F.Paste")
			(net "PVDDCR_CPU1_P0_PWM4")
		)
		(pad "35" smd rect
			(at -0.189992 -2.899918)
			(size 0.2286 0.6096)
			(layers "F.Cu" "F.Mask" "F.Paste")
			(net "PVDDCR_CPU1_P0_VCC4")
		)
		(pad "36" smd rect
			(at -0.64008 -2.899918)
			(size 0.2286 0.6096)
			(layers "F.Cu" "F.Mask" "F.Paste")
			(net "PVDDCR_CPU1_P0_TEMP0")
		)
		(pad "37" smd rect
			(at -1.089914 -2.899918)
			(size 0.2286 0.6096)
			(layers "F.Cu" "F.Mask" "F.Paste")
			(net "PVDDCR_CPU1_P0_LSET4")
		)
		(pad "38" smd rect
			(at -1.540002 -2.899918)
			(size 0.2286 0.6096)
			(layers "F.Cu" "F.Mask" "F.Paste")
			(net "PVDDCR_CPU1_P0_IMON4")
		)
		(pad "39" smd rect
			(at -1.99009 -2.899918)
			(size 0.2286 0.6096)
			(layers "F.Cu" "F.Mask" "F.Paste")
			(net "PVDDCR_CPU1_P0_VCCS")
		)
		(pad "40" smd rect
			(at -0.87503 -1.27508)
			(size 1.7526 1.9558)
			(layers "F.Cu" "F.Mask" "F.Paste")
			(net "GND")
		)
		(pad "41" smd rect
			(at -1.525016 0.249936 270)
			(size 0.3048 0.4572)
			(layers "F.Cu" "F.Mask" "F.Paste")
			(net "NC_PVDDCR_CPU1_P0_GL2_4")
		)
		(zone
			(layer "F.Cu")
			(hatch none 0.5)
			(connect_pads
				(clearance 0)
			)
			(min_thickness 0.25)
			(keepout
				(tracks not_allowed)
				(vias allowed)
				(pads allowed)
				(copperpour not_allowed)
				(footprints allowed)
			)
			(placement
				(enabled no)
				(sheetname "")
			)
			(fill
				(thermal_gap 0.5)
				(thermal_bridge_width 0.5)
				(island_removal_mode 0)
			)
			(polygon
				(pts
					(xy 306.195984 -344.147394) (xy 306.195984 -344.465656) (xy 311.196228 -344.465656) (xy 311.196228 -344.136472)
					(xy 310.905906 -344.136472) (xy 310.905906 -344.172032) (xy 306.486306 -344.172032) (xy 306.486306 -344.147394)
				)
			)
		)
		(zone
			(layer "F.Cu")
			(hatch none 0.5)
			(connect_pads
				(clearance 0)
			)
			(min_thickness 0.25)
			(keepout
				(tracks not_allowed)
				(vias allowed)
				(pads allowed)
				(copperpour not_allowed)
				(footprints allowed)
			)
			(placement
				(enabled no)
				(sheetname "")
			)
			(fill
				(thermal_gap 0.5)
				(thermal_bridge_width 0.5)
				(island_removal_mode 0)
			)
			(polygon
				(pts
					(xy 308.748176 -346.96273) (xy 308.748176 -349.02013) (xy 306.893976 -349.02013) (xy 306.893976 -348.779084)
					(xy 306.65166 -348.779084) (xy 306.65166 -349.260668) (xy 310.491886 -349.260668) (xy 310.491886 -349.075756)
					(xy 309.039514 -349.075756) (xy 309.039514 -346.916756) (xy 311.196228 -346.916756) (xy 311.196228 -346.667074)
					(xy 309.043832 -346.667074)
				)
			)
		)
	)
	(footprint ""
		(layer "F.Cu")
		(at 390.162542 -416.899344 -90)
		(property "Reference" "C6577"
			(at 0 0 270)
			(layer "F.SilkS")
			(hide yes)
			(effects
				(font
					(size 1.27 1.27)
				)
			)
		)
		(property "Value" ""
			(at 0 0 270)
			(layer "F.Fab")
			(effects
				(font
					(size 1.27 1.27)
				)
			)
		)
		(duplicate_pad_numbers_are_jumpers no)
		(fp_line
			(start -0.299974 0.150114)
			(end -0.299974 -0.150114)
			(stroke
				(width 0.1)
				(type default)
			)
			(layer "F.Fab")
		)
		(fp_line
			(start 0.299974 0.150114)
			(end -0.299974 0.150114)
			(stroke
				(width 0.1)
				(type default)
			)
			(layer "F.Fab")
		)
		(fp_line
			(start -0.299974 -0.150114)
			(end 0.299974 -0.150114)
			(stroke
				(width 0.1)
				(type default)
			)
			(layer "F.Fab")
		)
		(fp_line
			(start 0.299974 -0.150114)
			(end 0.299974 0.150114)
			(stroke
				(width 0.1)
				(type default)
			)
			(layer "F.Fab")
		)
		(pad "1" smd rect
			(at -0.2667 0 270)
			(size 0.3048 0.381)
			(layers "F.Cu" "F.Mask" "F.Paste")
			(net "P5E_CPU0_P2_TX_BUF_C_DP<6>")
		)
		(pad "2" smd rect
			(at 0.2667 0 270)
			(size 0.3048 0.381)
			(layers "F.Cu" "F.Mask" "F.Paste")
			(net "P5E_CPU0_P2_TX_BUF_DP<6>")
		)
	)
	(footprint ""
		(layer "F.Cu")
		(at 99.278186 -31.847536 -90)
		(property "Reference" "R6333"
			(at 0 0 270)
			(layer "F.SilkS")
			(hide yes)
			(effects
				(font
					(size 1.27 1.27)
				)
			)
		)
		(property "Value" ""
			(at 0 0 270)
			(layer "F.Fab")
			(effects
				(font
					(size 1.27 1.27)
				)
			)
		)
		(duplicate_pad_numbers_are_jumpers no)
		(fp_line
			(start -0.7874 0.4064)
			(end -0.7874 -0.4064)
			(stroke
				(width 0.1524)
				(type default)
			)
			(layer "F.SilkS")
		)
		(fp_line
			(start 0.7874 0.4064)
			(end -0.7874 0.4064)
			(stroke
				(width 0.1524)
				(type default)
			)
			(layer "F.SilkS")
		)
		(fp_line
			(start -0.7874 -0.4064)
			(end 0.7874 -0.4064)
			(stroke
				(width 0.1524)
				(type default)
			)
			(layer "F.SilkS")
		)
		(fp_line
			(start 0.7874 -0.4064)
			(end 0.7874 0.4064)
			(stroke
				(width 0.1524)
				(type default)
			)
			(layer "F.SilkS")
		)
		(fp_line
			(start -0.67945 0.3048)
			(end -0.67945 -0.305054)
			(stroke
				(width 0.1)
				(type default)
			)
			(layer "F.Fab")
		)
		(fp_line
			(start -0.12065 0.3048)
			(end -0.67945 0.3048)
			(stroke
				(width 0.1)
				(type default)
			)
			(layer "F.Fab")
		)
		(fp_line
			(start 0.120396 0.3048)
			(end 0.120396 0.2794)
			(stroke
				(width 0.1)
				(type default)
			)
			(layer "F.Fab")
		)
		(fp_line
			(start 0.67945 0.3048)
			(end 0.120396 0.3048)
			(stroke
				(width 0.1)
				(type default)
			)
			(layer "F.Fab")
		)
		(fp_line
			(start -0.12065 0.2794)
			(end -0.12065 0.3048)
			(stroke
				(width 0.1)
				(type default)
			)
			(layer "F.Fab")
		)
		(fp_line
			(start 0.120396 0.2794)
			(end -0.12065 0.2794)
			(stroke
				(width 0.1)
				(type default)
			)
			(layer "F.Fab")
		)
		(fp_line
			(start -0.12065 -0.2794)
			(end 0.12065 -0.2794)
			(stroke
				(width 0.1)
				(type default)
			)
			(layer "F.Fab")
		)
		(fp_line
			(start 0.12065 -0.2794)
			(end 0.12065 -0.3048)
			(stroke
				(width 0.1)
				(type default)
			)
			(layer "F.Fab")
		)
		(fp_line
			(start 0.12065 -0.3048)
			(end 0.67945 -0.3048)
			(stroke
				(width 0.1)
				(type default)
			)
			(layer "F.Fab")
		)
		(fp_line
			(start 0.67945 -0.3048)
			(end 0.67945 0.3048)
			(stroke
				(width 0.1)
				(type default)
			)
			(layer "F.Fab")
		)
		(fp_line
			(start -0.67945 -0.305054)
			(end -0.12065 -0.305054)
			(stroke
				(width 0.1)
				(type default)
			)
			(layer "F.Fab")
		)
		(fp_line
			(start -0.12065 -0.305054)
			(end -0.12065 -0.2794)
			(stroke
				(width 0.1)
				(type default)
			)
			(layer "F.Fab")
		)
		(pad "1" smd circle
			(at -0.40005 0 270)
			(size 0 0)
			(layers "F.Cu" "F.Mask" "F.Paste")
			(net "USB_HUB2_TI_GRSTZ_MRP_PROG_FUNC1")
		)
		(pad "2" smd circle
			(at 0.40005 0 270)
			(size 0 0)
			(layers "F.Cu" "F.Mask" "F.Paste")
			(net "GND")
		)
	)
	(footprint ""
		(layer "F.Cu")
		(at 309.894986 -416.899344 -90)
		(property "Reference" "C6506"
			(at 0 0 270)
			(layer "F.SilkS")
			(hide yes)
			(effects
				(font
					(size 1.27 1.27)
				)
			)
		)
		(property "Value" ""
			(at 0 0 270)
			(layer "F.Fab")
			(effects
				(font
					(size 1.27 1.27)
				)
			)
		)
		(duplicate_pad_numbers_are_jumpers no)
		(fp_line
			(start -0.299974 0.150114)
			(end -0.299974 -0.150114)
			(stroke
				(width 0.1)
				(type default)
			)
			(layer "F.Fab")
		)
		(fp_line
			(start 0.299974 0.150114)
			(end -0.299974 0.150114)
			(stroke
				(width 0.1)
				(type default)
			)
			(layer "F.Fab")
		)
		(fp_line
			(start -0.299974 -0.150114)
			(end 0.299974 -0.150114)
			(stroke
				(width 0.1)
				(type default)
			)
			(layer "F.Fab")
		)
		(fp_line
			(start 0.299974 -0.150114)
			(end 0.299974 0.150114)
			(stroke
				(width 0.1)
				(type default)
			)
			(layer "F.Fab")
		)
		(pad "1" smd rect
			(at -0.2667 0 270)
			(size 0.3048 0.381)
			(layers "F.Cu" "F.Mask" "F.Paste")
			(net "P5E_CPU0_P0_TX_BUF_C_DN<2>")
		)
		(pad "2" smd rect
			(at 0.2667 0 270)
			(size 0.3048 0.381)
			(layers "F.Cu" "F.Mask" "F.Paste")
			(net "P5E_CPU0_P0_TX_BUF_DN<2>")
		)
	)
	(footprint ""
		(layer "F.Cu")
		(at 333.376524 -24.771858 -90)
		(property "Reference" "C5032"
			(at 0 0 270)
			(layer "F.SilkS")
			(hide yes)
			(effects
				(font
					(size 1.27 1.27)
				)
			)
		)
		(property "Value" ""
			(at 0 0 270)
			(layer "F.Fab")
			(effects
				(font
					(size 1.27 1.27)
				)
			)
		)
		(duplicate_pad_numbers_are_jumpers no)
		(fp_line
			(start -1.524 0.762)
			(end -1.524 -0.762)
			(stroke
				(width 0.1524)
				(type default)
			)
			(layer "F.SilkS")
		)
		(fp_line
			(start 1.524 0.762)
			(end -1.524 0.762)
			(stroke
				(width 0.1524)
				(type default)
			)
			(layer "F.SilkS")
		)
		(fp_line
			(start -1.524 -0.762)
			(end 1.524 -0.762)
			(stroke
				(width 0.1524)
				(type default)
			)
			(layer "F.SilkS")
		)
		(fp_line
			(start 1.524 -0.762)
			(end 1.524 0.762)
			(stroke
				(width 0.1524)
				(type default)
			)
			(layer "F.SilkS")
		)
		(fp_line
			(start -1.1049 0.724916)
			(end 1.1049 0.724916)
			(stroke
				(width 0.1)
				(type default)
			)
			(layer "F.Fab")
		)
		(fp_line
			(start 1.1049 0.724916)
			(end 1.1049 -0.724916)
			(stroke
				(width 0.1)
				(type default)
			)
			(layer "F.Fab")
		)
		(fp_line
			(start -1.1049 -0.724916)
			(end -1.1049 0.724916)
			(stroke
				(width 0.1)
				(type default)
			)
			(layer "F.Fab")
		)
		(fp_line
			(start 1.1049 -0.724916)
			(end -1.1049 -0.724916)
			(stroke
				(width 0.1)
				(type default)
			)
			(layer "F.Fab")
		)
		(pad "1" smd rect
			(at -0.889 0 90)
			(size 1.016 1.27)
			(layers "F.Cu" "F.Mask" "F.Paste")
			(net "P1V5_BAT")
		)
		(pad "2" smd rect
			(at 0.889 0 90)
			(size 1.016 1.27)
			(layers "F.Cu" "F.Mask" "F.Paste")
			(net "GND")
		)
	)
	(footprint ""
		(layer "F.Cu")
		(at 138.426952 -56.500014 180)
		(property "Reference" "R1658"
			(at 0 0 180)
			(layer "F.SilkS")
			(hide yes)
			(effects
				(font
					(size 1.27 1.27)
				)
			)
		)
		(property "Value" ""
			(at 0 0 180)
			(layer "F.Fab")
			(effects
				(font
					(size 1.27 1.27)
				)
			)
		)
		(duplicate_pad_numbers_are_jumpers no)
		(fp_line
			(start 0.7874 0.4064)
			(end -0.7874 0.4064)
			(stroke
				(width 0.1524)
				(type default)
			)
			(layer "F.SilkS")
		)
		(fp_line
			(start 0.7874 -0.4064)
			(end 0.7874 0.4064)
			(stroke
				(width 0.1524)
				(type default)
			)
			(layer "F.SilkS")
		)
		(fp_line
			(start -0.7874 0.4064)
			(end -0.7874 -0.4064)
			(stroke
				(width 0.1524)
				(type default)
			)
			(layer "F.SilkS")
		)
		(fp_line
			(start -0.7874 -0.4064)
			(end 0.7874 -0.4064)
			(stroke
				(width 0.1524)
				(type default)
			)
			(layer "F.SilkS")
		)
		(fp_line
			(start 0.67945 0.3048)
			(end 0.120396 0.3048)
			(stroke
				(width 0.1)
				(type default)
			)
			(layer "F.Fab")
		)
		(fp_line
			(start 0.67945 -0.3048)
			(end 0.67945 0.3048)
			(stroke
				(width 0.1)
				(type default)
			)
			(layer "F.Fab")
		)
		(fp_line
			(start 0.12065 -0.2794)
			(end 0.12065 -0.3048)
			(stroke
				(width 0.1)
				(type default)
			)
			(layer "F.Fab")
		)
		(fp_line
			(start 0.12065 -0.3048)
			(end 0.67945 -0.3048)
			(stroke
				(width 0.1)
				(type default)
			)
			(layer "F.Fab")
		)
		(fp_line
			(start 0.120396 0.3048)
			(end 0.120396 0.2794)
			(stroke
				(width 0.1)
				(type default)
			)
			(layer "F.Fab")
		)
		(fp_line
			(start 0.120396 0.2794)
			(end -0.12065 0.2794)
			(stroke
				(width 0.1)
				(type default)
			)
			(layer "F.Fab")
		)
		(fp_line
			(start -0.12065 0.3048)
			(end -0.67945 0.3048)
			(stroke
				(width 0.1)
				(type default)
			)
			(layer "F.Fab")
		)
		(fp_line
			(start -0.12065 0.2794)
			(end -0.12065 0.3048)
			(stroke
				(width 0.1)
				(type default)
			)
			(layer "F.Fab")
		)
		(fp_line
			(start -0.12065 -0.2794)
			(end 0.12065 -0.2794)
			(stroke
				(width 0.1)
				(type default)
			)
			(layer "F.Fab")
		)
		(fp_line
			(start -0.12065 -0.305054)
			(end -0.12065 -0.2794)
			(stroke
				(width 0.1)
				(type default)
			)
			(layer "F.Fab")
		)
		(fp_line
			(start -0.67945 0.3048)
			(end -0.67945 -0.305054)
			(stroke
				(width 0.1)
				(type default)
			)
			(layer "F.Fab")
		)
		(fp_line
			(start -0.67945 -0.305054)
			(end -0.12065 -0.305054)
			(stroke
				(width 0.1)
				(type default)
			)
			(layer "F.Fab")
		)
		(pad "1" smd circle
			(at -0.40005 0 180)
			(size 0 0)
			(layers "F.Cu" "F.Mask" "F.Paste")
			(net "SCM_JTAG_MUX_S0")
		)
		(pad "2" smd circle
			(at 0.40005 0 180)
			(size 0 0)
			(layers "F.Cu" "F.Mask" "F.Paste")
			(net "GND")
		)
	)
)
